# SCM (Grand Teton) — schematic netlist excerpt (pin names and nets, part order shuffled) for the footprints in the layout excerpt that follows; sources: Cadence DE-HDL packaged netlist, KiCad conversion of 12092022_DA0F0TMDCD0_F0T_Management_Board_D_brd_V3_OCP.brd

C97  Q_CAP  0.1UF 25V 10% X7R  pkg 0402  page 17 : A = P1V0_STBY_DP_VCC10A ; B = GND
C210  Q_CAP  22PF 50V 5% NPO  pkg 0402  page 23 : A = V_DACB_IO ; B = GND

(kicad_pcb
	(version 20260206)
	(generator "pcbnew")
	(generator_version "10.0")
	(general
		(thickness 1.6)
		(legacy_teardrops no)
	)
	(paper "A4")
	(title_block
		(title "12092022_DA0F0TMDCD0_F0T_Management_Board_D_brd_V3_OCP.brd")
		(comment 1 "Grand Teton / footprints 1351-1352 of 1440")
	)
	(layers
		(0 "F.Cu" signal "TOP")
		(4 "In1.Cu" signal "GND")
		(6 "In2.Cu" signal "IN1")
		(8 "In3.Cu" signal "GND1")
		(10 "In4.Cu" signal "IN2")
		(12 "In5.Cu" signal "VCC")
		(14 "In6.Cu" signal "VCC1")
		(16 "In7.Cu" signal "IN3")
		(18 "In8.Cu" signal "GND2")
		(20 "In9.Cu" signal "IN4")
		(22 "In10.Cu" signal "GND3")
		(2 "B.Cu" signal "BOTTOM")
		(9 "F.Adhes" user "F.Adhesive")
		(11 "B.Adhes" user "B.Adhesive")
		(13 "F.Paste" user "Package Geometry/Pastemask Top")
		(15 "B.Paste" user "Package Geometry/Pastemask Bottom")
		(5 "F.SilkS" user "Ref Des/Silkscreen Top")
		(7 "B.SilkS" user "Ref Des/Silkscreen Bottom")
		(1 "F.Mask" user "Board Geometry/Soldermask Top")
		(3 "B.Mask" user "Board Geometry/Soldermask Bottom")
		(17 "Dwgs.User" user "User.Drawings")
		(19 "Cmts.User" user "User.Comments")
		(21 "Eco1.User" user "User.Eco1")
		(23 "Eco2.User" user "User.Eco2")
		(25 "Edge.Cuts" user "Board Geometry/Outline")
		(27 "Margin" user)
		(31 "F.CrtYd" user "Package Geometry/Place Bound Top")
		(29 "B.CrtYd" user "Package Geometry/Place Bound Bottom")
		(35 "F.Fab" user "Ref Des/Assembly Top")
		(33 "B.Fab" user "Ref Des/Assembly Bottom")
	)
	(footprint ""
		(layer "B.Cu")
		(at 32.893 -29.972 -90)
		(property "Reference" "C210"
			(at 0 0 90)
			(layer "B.SilkS")
			(hide yes)
			(effects
				(font
					(size 1.27 1.27)
				)
				(justify mirror)
			)
		)
		(property "Value" ""
			(at 0 0 90)
			(layer "B.Fab")
			(effects
				(font
					(size 1.27 1.27)
				)
				(justify mirror)
			)
		)
		(duplicate_pad_numbers_are_jumpers no)
		(fp_line
			(start -0.7874 0.406146)
			(end 0.7874 0.406146)
			(stroke
				(width 0.1524)
				(type default)
			)
			(layer "B.SilkS")
		)
		(fp_line
			(start 0.7874 0.406146)
			(end 0.7874 -0.406146)
			(stroke
				(width 0.1524)
				(type default)
			)
			(layer "B.SilkS")
		)
		(fp_line
			(start -0.7874 -0.406146)
			(end -0.7874 0.406146)
			(stroke
				(width 0.1524)
				(type default)
			)
			(layer "B.SilkS")
		)
		(fp_line
			(start 0.7874 -0.406146)
			(end -0.7874 -0.406146)
			(stroke
				(width 0.1524)
				(type default)
			)
			(layer "B.SilkS")
		)
		(fp_line
			(start -0.67945 0.3048)
			(end -0.120396 0.3048)
			(stroke
				(width 0.1)
				(type default)
			)
			(layer "B.Fab")
		)
		(fp_line
			(start -0.120396 0.3048)
			(end -0.120396 0.2794)
			(stroke
				(width 0.1)
				(type default)
			)
			(layer "B.Fab")
		)
		(fp_line
			(start 0.120396 0.3048)
			(end 0.67945 0.3048)
			(stroke
				(width 0.1)
				(type default)
			)
			(layer "B.Fab")
		)
		(fp_line
			(start 0.67945 0.3048)
			(end 0.67945 -0.305054)
			(stroke
				(width 0.1)
				(type default)
			)
			(layer "B.Fab")
		)
		(fp_line
			(start -0.120396 0.2794)
			(end 0.12065 0.2794)
			(stroke
				(width 0.1)
				(type default)
			)
			(layer "B.Fab")
		)
		(fp_line
			(start 0.12065 0.2794)
			(end 0.120396 0.3048)
			(stroke
				(width 0.1)
				(type default)
			)
			(layer "B.Fab")
		)
		(fp_line
			(start -0.12065 -0.2794)
			(end -0.120396 -0.3048)
			(stroke
				(width 0.1)
				(type default)
			)
			(layer "B.Fab")
		)
		(fp_line
			(start 0.12065 -0.2794)
			(end -0.12065 -0.2794)
			(stroke
				(width 0.1)
				(type default)
			)
			(layer "B.Fab")
		)
		(fp_line
			(start -0.67945 -0.3048)
			(end -0.67945 0.3048)
			(stroke
				(width 0.1)
				(type default)
			)
			(layer "B.Fab")
		)
		(fp_line
			(start -0.120396 -0.3048)
			(end -0.67945 -0.3048)
			(stroke
				(width 0.1)
				(type default)
			)
			(layer "B.Fab")
		)
		(fp_line
			(start 0.12065 -0.305054)
			(end 0.12065 -0.2794)
			(stroke
				(width 0.1)
				(type default)
			)
			(layer "B.Fab")
		)
		(fp_line
			(start 0.67945 -0.305054)
			(end 0.12065 -0.305054)
			(stroke
				(width 0.1)
				(type default)
			)
			(layer "B.Fab")
		)
		(pad "1" smd circle
			(at 0.40005 0 90)
			(size 0 0)
			(layers "B.Cu" "B.Mask" "B.Paste")
			(net "V_DACB_IO")
		)
		(pad "2" smd circle
			(at -0.40005 0 90)
			(size 0 0)
			(layers "B.Cu" "B.Mask" "B.Paste")
			(net "GND")
		)
	)
	(footprint ""
		(layer "B.Cu")
		(at 58.726832 -52.58816)
		(property "Reference" "C97"
			(at 0 0 0)
			(layer "B.SilkS")
			(hide yes)
			(effects
				(font
					(size 1.27 1.27)
				)
				(justify mirror)
			)
		)
		(property "Value" ""
			(at 0 0 0)
			(layer "B.Fab")
			(effects
				(font
					(size 1.27 1.27)
				)
				(justify mirror)
			)
		)
		(duplicate_pad_numbers_are_jumpers no)
		(fp_line
			(start -0.7874 -0.4064)
			(end -0.7874 0.4064)
			(stroke
				(width 0.1524)
				(type default)
			)
			(layer "B.SilkS")
		)
		(fp_line
			(start -0.7874 0.4064)
			(end 0.7874 0.4064)
			(stroke
				(width 0.1524)
				(type default)
			)
			(layer "B.SilkS")
		)
		(fp_line
			(start 0.7874 -0.4064)
			(end -0.7874 -0.4064)
			(stroke
				(width 0.1524)
				(type default)
			)
			(layer "B.SilkS")
		)
		(fp_line
			(start 0.7874 0.4064)
			(end 0.7874 -0.4064)
			(stroke
				(width 0.1524)
				(type default)
			)
			(layer "B.SilkS")
		)
		(fp_line
			(start -0.67945 -0.3048)
			(end -0.67945 0.3048)
			(stroke
				(width 0.1)
				(type default)
			)
			(layer "B.Fab")
		)
		(fp_line
			(start -0.67945 0.3048)
			(end -0.120396 0.3048)
			(stroke
				(width 0.1)
				(type default)
			)
			(layer "B.Fab")
		)
		(fp_line
			(start -0.12065 -0.3048)
			(end -0.67945 -0.3048)
			(stroke
				(width 0.1)
				(type default)
			)
			(layer "B.Fab")
		)
		(fp_line
			(start -0.12065 -0.2794)
			(end -0.12065 -0.3048)
			(stroke
				(width 0.1)
				(type default)
			)
			(layer "B.Fab")
		)
		(fp_line
			(start -0.120396 0.2794)
			(end 0.12065 0.2794)
			(stroke
				(width 0.1)
				(type default)
			)
			(layer "B.Fab")
		)
		(fp_line
			(start -0.120396 0.3048)
			(end -0.120396 0.2794)
			(stroke
				(width 0.1)
				(type default)
			)
			(layer "B.Fab")
		)
		(fp_line
			(start 0.12065 -0.305054)
			(end 0.12065 -0.2794)
			(stroke
				(width 0.1)
				(type default)
			)
			(layer "B.Fab")
		)
		(fp_line
			(start 0.12065 -0.2794)
			(end -0.12065 -0.2794)
			(stroke
				(width 0.1)
				(type default)
			)
			(layer "B.Fab")
		)
		(fp_line
			(start 0.12065 0.2794)
			(end 0.12065 0.3048)
			(stroke
				(width 0.1)
				(type default)
			)
			(layer "B.Fab")
		)
		(fp_line
			(start 0.12065 0.3048)
			(end 0.67945 0.3048)
			(stroke
				(width 0.1)
				(type default)
			)
			(layer "B.Fab")
		)
		(fp_line
			(start 0.67945 -0.305054)
			(end 0.12065 -0.305054)
			(stroke
				(width 0.1)
				(type default)
			)
			(layer "B.Fab")
		)
		(fp_line
			(start 0.67945 0.3048)
			(end 0.67945 -0.305054)
			(stroke
				(width 0.1)
				(type default)
			)
			(layer "B.Fab")
		)
		(pad "1" smd circle
			(at 0.40005 0 180)
			(size 0 0)
			(layers "B.Cu" "B.Mask" "B.Paste")
			(net "P1V0_STBY_DP_VCC10A")
		)
		(pad "2" smd circle
			(at -0.40005 0 180)
			(size 0 0)
			(layers "B.Cu" "B.Mask" "B.Paste")
			(net "GND")
		)
	)
)
